# T6G (Grand Teton) — schematic netlist excerpt (pin names and nets, part order shuffled) for the footprints in the layout excerpt that follows; sources: Cadence DE-HDL packaged netlist, KiCad conversion of 04192023_DAF0TMB3IC0_F0TG_MB_C_brd_V02_OCP.brd

R878  Q_RES  4.7K 5% EMPTY  pkg 0201LF  page 342 : A = P1V8_CPU1_RT_1D ; B = TEST0_RT_CPU1_P2
C6675  Q_CAP_DIFFBUS  DIFF BUS_0.22UF 6.3V 20% X6S  pkg C0201  page 330 : \1\ = P5E_CPU1_P1_TX_BUF_C_DP<7> ; \2\ = P5E_CPU1_P1_TX_BUF_DP<7>
C587  Q_CAP  100UF 4V 20% X6S  pkg C0805  page 290 : A = P1V8_CPU0_RT_1D ; B = GND
R3242  Q_RES  2.2K 5% EMPTY  pkg 0402LF  page 151 : A = SMB_OCP_V3_2_3V3AUX_SCL ; B = P3V3_AUX

(kicad_pcb
	(version 20260206)
	(generator "pcbnew")
	(generator_version "10.0")
	(general
		(thickness 1.6)
		(legacy_teardrops no)
	)
	(paper "A4")
	(title_block
		(title "04192023_DAF0TMB3IC0_F0TG_MB_C_brd_V02_OCP.brd")
		(comment 1 "Grand Teton / footprints 6479-6482 of 8354")
	)
	(layers
		(0 "F.Cu" signal "TOP")
		(4 "In1.Cu" signal "GND")
		(6 "In2.Cu" signal "IN1")
		(8 "In3.Cu" signal "GND1")
		(10 "In4.Cu" signal "IN2")
		(12 "In5.Cu" signal "GND2")
		(14 "In6.Cu" signal "IN3")
		(16 "In7.Cu" signal "GND3")
		(18 "In8.Cu" signal "VCC")
		(20 "In9.Cu" signal "VCC1")
		(22 "In10.Cu" signal "GND4")
		(24 "In11.Cu" signal "IN4")
		(26 "In12.Cu" signal "GND5")
		(28 "In13.Cu" signal "IN5")
		(30 "In14.Cu" signal "GND6")
		(32 "In15.Cu" signal "IN6")
		(34 "In16.Cu" signal "GND7")
		(2 "B.Cu" signal "BOTTOM")
		(9 "F.Adhes" user "F.Adhesive")
		(11 "B.Adhes" user "B.Adhesive")
		(13 "F.Paste" user "Package Geometry/Pastemask Top")
		(15 "B.Paste" user "Package Geometry/Pastemask Bottom")
		(5 "F.SilkS" user "Ref Des/Silkscreen Top")
		(7 "B.SilkS" user "Ref Des/Silkscreen Bottom")
		(1 "F.Mask" user "Board Geometry/Soldermask Top")
		(3 "B.Mask" user "Board Geometry/Soldermask Bottom")
		(17 "Dwgs.User" user "User.Drawings")
		(19 "Cmts.User" user "User.Comments")
		(21 "Eco1.User" user "User.Eco1")
		(23 "Eco2.User" user "User.Eco2")
		(25 "Edge.Cuts" user "Board Geometry/Outline")
		(27 "Margin" user)
		(31 "F.CrtYd" user "Package Geometry/Place Bound Top")
		(29 "B.CrtYd" user "Package Geometry/Place Bound Bottom")
		(35 "F.Fab" user "Ref Des/Assembly Top")
		(33 "B.Fab" user "Ref Des/Assembly Bottom")
	)
	(footprint ""
		(layer "B.Cu")
		(at 172.877734 -8.062468 -90)
		(property "Reference" "R3242"
			(at 0 0 90)
			(layer "B.SilkS")
			(hide yes)
			(effects
				(font
					(size 1.27 1.27)
				)
				(justify mirror)
			)
		)
		(property "Value" ""
			(at 0 0 90)
			(layer "B.Fab")
			(effects
				(font
					(size 1.27 1.27)
				)
				(justify mirror)
			)
		)
		(duplicate_pad_numbers_are_jumpers no)
		(fp_line
			(start -0.7874 0.4064)
			(end 0.7874 0.4064)
			(stroke
				(width 0.1524)
				(type default)
			)
			(layer "B.SilkS")
		)
		(fp_line
			(start 0.7874 0.4064)
			(end 0.7874 -0.4064)
			(stroke
				(width 0.1524)
				(type default)
			)
			(layer "B.SilkS")
		)
		(fp_line
			(start -0.7874 -0.4064)
			(end -0.7874 0.4064)
			(stroke
				(width 0.1524)
				(type default)
			)
			(layer "B.SilkS")
		)
		(fp_line
			(start 0.7874 -0.4064)
			(end -0.7874 -0.4064)
			(stroke
				(width 0.1524)
				(type default)
			)
			(layer "B.SilkS")
		)
		(fp_line
			(start -0.67945 0.3048)
			(end -0.120396 0.3048)
			(stroke
				(width 0.1)
				(type default)
			)
			(layer "B.Fab")
		)
		(fp_line
			(start -0.120396 0.3048)
			(end -0.120396 0.2794)
			(stroke
				(width 0.1)
				(type default)
			)
			(layer "B.Fab")
		)
		(fp_line
			(start 0.12065 0.3048)
			(end 0.67945 0.3048)
			(stroke
				(width 0.1)
				(type default)
			)
			(layer "B.Fab")
		)
		(fp_line
			(start 0.67945 0.3048)
			(end 0.67945 -0.305054)
			(stroke
				(width 0.1)
				(type default)
			)
			(layer "B.Fab")
		)
		(fp_line
			(start -0.120396 0.2794)
			(end 0.12065 0.2794)
			(stroke
				(width 0.1)
				(type default)
			)
			(layer "B.Fab")
		)
		(fp_line
			(start 0.12065 0.2794)
			(end 0.12065 0.3048)
			(stroke
				(width 0.1)
				(type default)
			)
			(layer "B.Fab")
		)
		(fp_line
			(start -0.12065 -0.2794)
			(end -0.12065 -0.3048)
			(stroke
				(width 0.1)
				(type default)
			)
			(layer "B.Fab")
		)
		(fp_line
			(start 0.12065 -0.2794)
			(end -0.12065 -0.2794)
			(stroke
				(width 0.1)
				(type default)
			)
			(layer "B.Fab")
		)
		(fp_line
			(start -0.67945 -0.3048)
			(end -0.67945 0.3048)
			(stroke
				(width 0.1)
				(type default)
			)
			(layer "B.Fab")
		)
		(fp_line
			(start -0.12065 -0.3048)
			(end -0.67945 -0.3048)
			(stroke
				(width 0.1)
				(type default)
			)
			(layer "B.Fab")
		)
		(fp_line
			(start 0.12065 -0.305054)
			(end 0.12065 -0.2794)
			(stroke
				(width 0.1)
				(type default)
			)
			(layer "B.Fab")
		)
		(fp_line
			(start 0.67945 -0.305054)
			(end 0.12065 -0.305054)
			(stroke
				(width 0.1)
				(type default)
			)
			(layer "B.Fab")
		)
		(pad "1" smd circle
			(at 0.40005 0 90)
			(size 0 0)
			(layers "B.Cu" "B.Mask" "B.Paste")
			(net "SMB_OCP_V3_2_3V3AUX_SCL")
		)
		(pad "2" smd circle
			(at -0.40005 0 90)
			(size 0 0)
			(layers "B.Cu" "B.Mask" "B.Paste")
			(net "P3V3_AUX")
		)
	)
	(footprint ""
		(layer "B.Cu")
		(at 359.173018 -395.466062 -90)
		(property "Reference" "C587"
			(at 0 0 90)
			(layer "B.SilkS")
			(hide yes)
			(effects
				(font
					(size 1.27 1.27)
				)
				(justify mirror)
			)
		)
		(property "Value" ""
			(at 0 0 90)
			(layer "B.Fab")
			(effects
				(font
					(size 1.27 1.27)
				)
				(justify mirror)
			)
		)
		(duplicate_pad_numbers_are_jumpers no)
		(fp_line
			(start -1.524 0.762)
			(end 1.524 0.762)
			(stroke
				(width 0.1524)
				(type default)
			)
			(layer "B.SilkS")
		)
		(fp_line
			(start 1.524 0.762)
			(end 1.524 -0.762)
			(stroke
				(width 0.1524)
				(type default)
			)
			(layer "B.SilkS")
		)
		(fp_line
			(start -1.524 -0.762)
			(end -1.524 0.762)
			(stroke
				(width 0.1524)
				(type default)
			)
			(layer "B.SilkS")
		)
		(fp_line
			(start 1.524 -0.762)
			(end -1.524 -0.762)
			(stroke
				(width 0.1524)
				(type default)
			)
			(layer "B.SilkS")
		)
		(fp_line
			(start -1.1049 0.724916)
			(end -1.1049 -0.724916)
			(stroke
				(width 0.1)
				(type default)
			)
			(layer "B.Fab")
		)
		(fp_line
			(start 1.1049 0.724916)
			(end -1.1049 0.724916)
			(stroke
				(width 0.1)
				(type default)
			)
			(layer "B.Fab")
		)
		(fp_line
			(start -1.1049 -0.724916)
			(end 1.1049 -0.724916)
			(stroke
				(width 0.1)
				(type default)
			)
			(layer "B.Fab")
		)
		(fp_line
			(start 1.1049 -0.724916)
			(end 1.1049 0.724916)
			(stroke
				(width 0.1)
				(type default)
			)
			(layer "B.Fab")
		)
		(pad "1" smd rect
			(at 0.889 0 270)
			(size 1.016 1.27)
			(layers "B.Cu" "B.Mask" "B.Paste")
			(net "P1V8_CPU0_RT_1D")
		)
		(pad "2" smd rect
			(at -0.889 0 270)
			(size 1.016 1.27)
			(layers "B.Cu" "B.Mask" "B.Paste")
			(net "GND")
		)
	)
	(footprint ""
		(layer "B.Cu")
		(at 141.623542 -385.58216 180)
		(property "Reference" "R878"
			(at 0 0 0)
			(layer "B.SilkS")
			(hide yes)
			(effects
				(font
					(size 1.27 1.27)
				)
				(justify mirror)
			)
		)
		(property "Value" ""
			(at 0 0 0)
			(layer "B.Fab")
			(effects
				(font
					(size 1.27 1.27)
				)
				(justify mirror)
			)
		)
		(duplicate_pad_numbers_are_jumpers no)
		(fp_line
			(start 0.32512 0.175006)
			(end 0.32512 -0.175006)
			(stroke
				(width 0.1)
				(type default)
			)
			(layer "B.Fab")
		)
		(fp_line
			(start 0.32512 -0.175006)
			(end -0.32512 -0.175006)
			(stroke
				(width 0.1)
				(type default)
			)
			(layer "B.Fab")
		)
		(fp_line
			(start -0.32512 0.175006)
			(end 0.32512 0.175006)
			(stroke
				(width 0.1)
				(type default)
			)
			(layer "B.Fab")
		)
		(fp_line
			(start -0.32512 -0.175006)
			(end -0.32512 0.175006)
			(stroke
				(width 0.1)
				(type default)
			)
			(layer "B.Fab")
		)
		(pad "1" smd rect
			(at 0.2667 0)
			(size 0.3048 0.381)
			(layers "B.Cu" "B.Mask" "B.Paste")
			(net "P1V8_CPU1_RT_1D")
		)
		(pad "2" smd rect
			(at -0.2667 0 180)
			(size 0.3048 0.381)
			(layers "B.Cu" "B.Mask" "B.Paste")
			(net "TEST0_RT_CPU1_P2")
		)
	)
	(footprint ""
		(layer "B.Cu")
		(at 71.657464 -408.517344 90)
		(property "Reference" "C6675"
			(at 0 0 90)
			(layer "B.SilkS")
			(hide yes)
			(effects
				(font
					(size 1.27 1.27)
				)
				(justify mirror)
			)
		)
		(property "Value" ""
			(at 0 0 90)
			(layer "B.Fab")
			(effects
				(font
					(size 1.27 1.27)
				)
				(justify mirror)
			)
		)
		(duplicate_pad_numbers_are_jumpers no)
		(fp_line
			(start 0.299974 -0.150114)
			(end -0.299974 -0.150114)
			(stroke
				(width 0.1)
				(type default)
			)
			(layer "B.Fab")
		)
		(fp_line
			(start -0.299974 -0.150114)
			(end -0.299974 0.150114)
			(stroke
				(width 0.1)
				(type default)
			)
			(layer "B.Fab")
		)
		(fp_line
			(start 0.299974 0.150114)
			(end 0.299974 -0.150114)
			(stroke
				(width 0.1)
				(type default)
			)
			(layer "B.Fab")
		)
		(fp_line
			(start -0.299974 0.150114)
			(end 0.299974 0.150114)
			(stroke
				(width 0.1)
				(type default)
			)
			(layer "B.Fab")
		)
		(pad "1" smd rect
			(at 0.2667 0 270)
			(size 0.3048 0.381)
			(layers "B.Cu" "B.Mask" "B.Paste")
			(net "P5E_CPU1_P1_TX_BUF_C_DP<7>")
		)
		(pad "2" smd rect
			(at -0.2667 0 270)
			(size 0.3048 0.381)
			(layers "B.Cu" "B.Mask" "B.Paste")
			(net "P5E_CPU1_P1_TX_BUF_DP<7>")
		)
	)
)
